# S9S_MB_2U (Grand Teton) — schematic netlist excerpt (pin names and nets, part order shuffled) for the footprints in the layout excerpt that follows; sources: Cadence DE-HDL packaged netlist, KiCad conversion of 03242023_DA0F0TMBIJ0_F0T_Motherboard_J_brd_V01_OCP.brd

R3217  Q_RES  100 1% CHIP  pkg 0402LF  page 160 : A = OCP_V3_2_ISO_BIF2_EN ; B = GND
R3721  Q_RES  0 5% CHIP  pkg 0402LF  page 233 : A = SMB_LM75_3_3V3AUX_SCL_R ; B = SMB_LM75_3_3V3AUX_SCL

(kicad_pcb
	(version 20260206)
	(generator "pcbnew")
	(generator_version "10.0")
	(general
		(thickness 1.6)
		(legacy_teardrops no)
	)
	(paper "A4")
	(title_block
		(title "03242023_DA0F0TMBIJ0_F0T_Motherboard_J_brd_V01_OCP.brd")
		(comment 1 "Grand Teton / footprints 2195-2196 of 6105")
	)
	(layers
		(0 "F.Cu" signal "TOP")
		(4 "In1.Cu" signal "GND")
		(6 "In2.Cu" signal "IN1")
		(8 "In3.Cu" signal "GND1")
		(10 "In4.Cu" signal "IN2")
		(12 "In5.Cu" signal "GND2")
		(14 "In6.Cu" signal "IN3")
		(16 "In7.Cu" signal "GND3")
		(18 "In8.Cu" signal "VCC")
		(20 "In9.Cu" signal "VCC1")
		(22 "In10.Cu" signal "GND4")
		(24 "In11.Cu" signal "IN4")
		(26 "In12.Cu" signal "GND5")
		(28 "In13.Cu" signal "IN5")
		(30 "In14.Cu" signal "GND6")
		(32 "In15.Cu" signal "IN6")
		(34 "In16.Cu" signal "GND7")
		(2 "B.Cu" signal "BOTTOM")
		(9 "F.Adhes" user "F.Adhesive")
		(11 "B.Adhes" user "B.Adhesive")
		(13 "F.Paste" user "Package Geometry/Pastemask Top")
		(15 "B.Paste" user "Package Geometry/Pastemask Bottom")
		(5 "F.SilkS" user "Ref Des/Silkscreen Top")
		(7 "B.SilkS" user "Ref Des/Silkscreen Bottom")
		(1 "F.Mask" user "Board Geometry/Soldermask Top")
		(3 "B.Mask" user "Board Geometry/Soldermask Bottom")
		(17 "Dwgs.User" user "User.Drawings")
		(19 "Cmts.User" user "User.Comments")
		(21 "Eco1.User" user "User.Eco1")
		(23 "Eco2.User" user "User.Eco2")
		(25 "Edge.Cuts" user "Board Geometry/Outline")
		(27 "Margin" user)
		(31 "F.CrtYd" user "Package Geometry/Place Bound Top")
		(29 "B.CrtYd" user "Package Geometry/Place Bound Bottom")
		(35 "F.Fab" user "Ref Des/Assembly Top")
		(33 "B.Fab" user "Ref Des/Assembly Bottom")
	)
	(footprint ""
		(layer "F.Cu")
		(at 61.90488 -18.252948)
		(property "Reference" "R3217"
			(at 0 0 0)
			(layer "F.SilkS")
			(hide yes)
			(effects
				(font
					(size 1.27 1.27)
				)
			)
		)
		(property "Value" ""
			(at 0 0 0)
			(layer "F.Fab")
			(effects
				(font
					(size 1.27 1.27)
				)
			)
		)
		(duplicate_pad_numbers_are_jumpers no)
		(fp_line
			(start -0.7874 -0.4064)
			(end 0.7874 -0.4064)
			(stroke
				(width 0.1524)
				(type default)
			)
			(layer "F.SilkS")
		)
		(fp_line
			(start -0.7874 0.4064)
			(end -0.7874 -0.4064)
			(stroke
				(width 0.1524)
				(type default)
			)
			(layer "F.SilkS")
		)
		(fp_line
			(start 0.7874 -0.4064)
			(end 0.7874 0.4064)
			(stroke
				(width 0.1524)
				(type default)
			)
			(layer "F.SilkS")
		)
		(fp_line
			(start 0.7874 0.4064)
			(end -0.7874 0.4064)
			(stroke
				(width 0.1524)
				(type default)
			)
			(layer "F.SilkS")
		)
		(fp_line
			(start -0.67945 -0.305054)
			(end -0.12065 -0.305054)
			(stroke
				(width 0.1)
				(type default)
			)
			(layer "F.Fab")
		)
		(fp_line
			(start -0.67945 0.3048)
			(end -0.67945 -0.305054)
			(stroke
				(width 0.1)
				(type default)
			)
			(layer "F.Fab")
		)
		(fp_line
			(start -0.12065 -0.305054)
			(end -0.12065 -0.2794)
			(stroke
				(width 0.1)
				(type default)
			)
			(layer "F.Fab")
		)
		(fp_line
			(start -0.12065 -0.2794)
			(end 0.12065 -0.2794)
			(stroke
				(width 0.1)
				(type default)
			)
			(layer "F.Fab")
		)
		(fp_line
			(start -0.12065 0.2794)
			(end -0.12065 0.3048)
			(stroke
				(width 0.1)
				(type default)
			)
			(layer "F.Fab")
		)
		(fp_line
			(start -0.12065 0.3048)
			(end -0.67945 0.3048)
			(stroke
				(width 0.1)
				(type default)
			)
			(layer "F.Fab")
		)
		(fp_line
			(start 0.120396 0.2794)
			(end -0.12065 0.2794)
			(stroke
				(width 0.1)
				(type default)
			)
			(layer "F.Fab")
		)
		(fp_line
			(start 0.120396 0.3048)
			(end 0.120396 0.2794)
			(stroke
				(width 0.1)
				(type default)
			)
			(layer "F.Fab")
		)
		(fp_line
			(start 0.12065 -0.3048)
			(end 0.67945 -0.3048)
			(stroke
				(width 0.1)
				(type default)
			)
			(layer "F.Fab")
		)
		(fp_line
			(start 0.12065 -0.2794)
			(end 0.12065 -0.3048)
			(stroke
				(width 0.1)
				(type default)
			)
			(layer "F.Fab")
		)
		(fp_line
			(start 0.67945 -0.3048)
			(end 0.67945 0.3048)
			(stroke
				(width 0.1)
				(type default)
			)
			(layer "F.Fab")
		)
		(fp_line
			(start 0.67945 0.3048)
			(end 0.120396 0.3048)
			(stroke
				(width 0.1)
				(type default)
			)
			(layer "F.Fab")
		)
		(pad "1" smd circle
			(at -0.40005 0)
			(size 0 0)
			(layers "F.Cu" "F.Mask" "F.Paste")
			(net "OCP_V3_2_ISO_BIF2_EN")
		)
		(pad "2" smd circle
			(at 0.40005 0)
			(size 0 0)
			(layers "F.Cu" "F.Mask" "F.Paste")
			(net "GND")
		)
	)
	(footprint ""
		(layer "F.Cu")
		(at 68.085716 -108.39069)
		(property "Reference" "R3721"
			(at 0 0 0)
			(layer "F.SilkS")
			(hide yes)
			(effects
				(font
					(size 1.27 1.27)
				)
			)
		)
		(property "Value" ""
			(at 0 0 0)
			(layer "F.Fab")
			(effects
				(font
					(size 1.27 1.27)
				)
			)
		)
		(duplicate_pad_numbers_are_jumpers no)
		(fp_line
			(start -0.7874 -0.4064)
			(end 0.7874 -0.4064)
			(stroke
				(width 0.1524)
				(type default)
			)
			(layer "F.SilkS")
		)
		(fp_line
			(start -0.7874 0.4064)
			(end -0.7874 -0.4064)
			(stroke
				(width 0.1524)
				(type default)
			)
			(layer "F.SilkS")
		)
		(fp_line
			(start 0.7874 -0.4064)
			(end 0.7874 0.4064)
			(stroke
				(width 0.1524)
				(type default)
			)
			(layer "F.SilkS")
		)
		(fp_line
			(start 0.7874 0.4064)
			(end -0.7874 0.4064)
			(stroke
				(width 0.1524)
				(type default)
			)
			(layer "F.SilkS")
		)
		(fp_line
			(start -0.67945 -0.305054)
			(end -0.12065 -0.305054)
			(stroke
				(width 0.1)
				(type default)
			)
			(layer "F.Fab")
		)
		(fp_line
			(start -0.67945 0.3048)
			(end -0.67945 -0.305054)
			(stroke
				(width 0.1)
				(type default)
			)
			(layer "F.Fab")
		)
		(fp_line
			(start -0.12065 -0.305054)
			(end -0.12065 -0.2794)
			(stroke
				(width 0.1)
				(type default)
			)
			(layer "F.Fab")
		)
		(fp_line
			(start -0.12065 -0.2794)
			(end 0.12065 -0.2794)
			(stroke
				(width 0.1)
				(type default)
			)
			(layer "F.Fab")
		)
		(fp_line
			(start -0.12065 0.2794)
			(end -0.12065 0.3048)
			(stroke
				(width 0.1)
				(type default)
			)
			(layer "F.Fab")
		)
		(fp_line
			(start -0.12065 0.3048)
			(end -0.67945 0.3048)
			(stroke
				(width 0.1)
				(type default)
			)
			(layer "F.Fab")
		)
		(fp_line
			(start 0.120396 0.2794)
			(end -0.12065 0.2794)
			(stroke
				(width 0.1)
				(type default)
			)
			(layer "F.Fab")
		)
		(fp_line
			(start 0.120396 0.3048)
			(end 0.120396 0.2794)
			(stroke
				(width 0.1)
				(type default)
			)
			(layer "F.Fab")
		)
		(fp_line
			(start 0.12065 -0.3048)
			(end 0.67945 -0.3048)
			(stroke
				(width 0.1)
				(type default)
			)
			(layer "F.Fab")
		)
		(fp_line
			(start 0.12065 -0.2794)
			(end 0.12065 -0.3048)
			(stroke
				(width 0.1)
				(type default)
			)
			(layer "F.Fab")
		)
		(fp_line
			(start 0.67945 -0.3048)
			(end 0.67945 0.3048)
			(stroke
				(width 0.1)
				(type default)
			)
			(layer "F.Fab")
		)
		(fp_line
			(start 0.67945 0.3048)
			(end 0.120396 0.3048)
			(stroke
				(width 0.1)
				(type default)
			)
			(layer "F.Fab")
		)
		(pad "1" smd circle
			(at -0.40005 0)
			(size 0 0)
			(layers "F.Cu" "F.Mask" "F.Paste")
			(net "SMB_LM75_3_3V3AUX_SCL_R")
		)
		(pad "2" smd circle
			(at 0.40005 0)
			(size 0 0)
			(layers "F.Cu" "F.Mask" "F.Paste")
			(net "SMB_LM75_3_3V3AUX_SCL")
		)
	)
)
